# T6G (Grand Teton) — schematic netlist excerpt (pin names and nets, part order shuffled) for the footprints in the layout excerpt that follows; sources: Cadence DE-HDL packaged netlist, KiCad conversion of 04192023_DAF0TMB3IC0_F0TG_MB_C_brd_V02_OCP.brd

C254  Q_CAP  10UF 6.3V 20% X6S  pkg C0402  page 323 : A = P0V9_CPU1_RT0_2A ; B = GND

(kicad_pcb
	(version 20260206)
	(generator "pcbnew")
	(generator_version "10.0")
	(general
		(thickness 1.6)
		(legacy_teardrops no)
	)
	(paper "A4")
	(title_block
		(title "04192023_DAF0TMB3IC0_F0TG_MB_C_brd_V02_OCP.brd")
		(comment 1 "Grand Teton / footprints 7825-7825 of 8354")
	)
	(layers
		(0 "F.Cu" signal "TOP")
		(4 "In1.Cu" signal "GND")
		(6 "In2.Cu" signal "IN1")
		(8 "In3.Cu" signal "GND1")
		(10 "In4.Cu" signal "IN2")
		(12 "In5.Cu" signal "GND2")
		(14 "In6.Cu" signal "IN3")
		(16 "In7.Cu" signal "GND3")
		(18 "In8.Cu" signal "VCC")
		(20 "In9.Cu" signal "VCC1")
		(22 "In10.Cu" signal "GND4")
		(24 "In11.Cu" signal "IN4")
		(26 "In12.Cu" signal "GND5")
		(28 "In13.Cu" signal "IN5")
		(30 "In14.Cu" signal "GND6")
		(32 "In15.Cu" signal "IN6")
		(34 "In16.Cu" signal "GND7")
		(2 "B.Cu" signal "BOTTOM")
		(9 "F.Adhes" user "F.Adhesive")
		(11 "B.Adhes" user "B.Adhesive")
		(13 "F.Paste" user "Package Geometry/Pastemask Top")
		(15 "B.Paste" user "Package Geometry/Pastemask Bottom")
		(5 "F.SilkS" user "Ref Des/Silkscreen Top")
		(7 "B.SilkS" user "Ref Des/Silkscreen Bottom")
		(1 "F.Mask" user "Board Geometry/Soldermask Top")
		(3 "B.Mask" user "Board Geometry/Soldermask Bottom")
		(17 "Dwgs.User" user "User.Drawings")
		(19 "Cmts.User" user "User.Comments")
		(21 "Eco1.User" user "User.Eco1")
		(23 "Eco2.User" user "User.Eco2")
		(25 "Edge.Cuts" user "Board Geometry/Outline")
		(27 "Margin" user)
		(31 "F.CrtYd" user "Package Geometry/Place Bound Top")
		(29 "B.CrtYd" user "Package Geometry/Place Bound Bottom")
		(35 "F.Fab" user "Ref Des/Assembly Top")
		(33 "B.Fab" user "Ref Des/Assembly Bottom")
	)
	(footprint ""
		(layer "B.Cu")
		(at 50.991262 -390.560052 90)
		(property "Reference" "C254"
			(at 0 0 90)
			(layer "B.SilkS")
			(hide yes)
			(effects
				(font
					(size 1.27 1.27)
				)
				(justify mirror)
			)
		)
		(property "Value" ""
			(at 0 0 90)
			(layer "B.Fab")
			(effects
				(font
					(size 1.27 1.27)
				)
				(justify mirror)
			)
		)
		(duplicate_pad_numbers_are_jumpers no)
		(fp_line
			(start 0.7874 -0.4064)
			(end -0.7874 -0.4064)
			(stroke
				(width 0.1524)
				(type default)
			)
			(layer "B.SilkS")
		)
		(fp_line
			(start -0.7874 -0.4064)
			(end -0.7874 0.4064)
			(stroke
				(width 0.1524)
				(type default)
			)
			(layer "B.SilkS")
		)
		(fp_line
			(start 0.7874 0.4064)
			(end 0.7874 -0.4064)
			(stroke
				(width 0.1524)
				(type default)
			)
			(layer "B.SilkS")
		)
		(fp_line
			(start -0.7874 0.4064)
			(end 0.7874 0.4064)
			(stroke
				(width 0.1524)
				(type default)
			)
			(layer "B.SilkS")
		)
		(fp_line
			(start 0.67945 -0.305054)
			(end 0.12065 -0.305054)
			(stroke
				(width 0.1)
				(type default)
			)
			(layer "B.Fab")
		)
		(fp_line
			(start 0.12065 -0.305054)
			(end 0.12065 -0.2794)
			(stroke
				(width 0.1)
				(type default)
			)
			(layer "B.Fab")
		)
		(fp_line
			(start -0.12065 -0.3048)
			(end -0.67945 -0.3048)
			(stroke
				(width 0.1)
				(type default)
			)
			(layer "B.Fab")
		)
		(fp_line
			(start -0.67945 -0.3048)
			(end -0.67945 0.3048)
			(stroke
				(width 0.1)
				(type default)
			)
			(layer "B.Fab")
		)
		(fp_line
			(start 0.12065 -0.2794)
			(end -0.12065 -0.2794)
			(stroke
				(width 0.1)
				(type default)
			)
			(layer "B.Fab")
		)
		(fp_line
			(start -0.12065 -0.2794)
			(end -0.12065 -0.3048)
			(stroke
				(width 0.1)
				(type default)
			)
			(layer "B.Fab")
		)
		(fp_line
			(start 0.12065 0.2794)
			(end 0.12065 0.3048)
			(stroke
				(width 0.1)
				(type default)
			)
			(layer "B.Fab")
		)
		(fp_line
			(start -0.120396 0.2794)
			(end 0.12065 0.2794)
			(stroke
				(width 0.1)
				(type default)
			)
			(layer "B.Fab")
		)
		(fp_line
			(start 0.67945 0.3048)
			(end 0.67945 -0.305054)
			(stroke
				(width 0.1)
				(type default)
			)
			(layer "B.Fab")
		)
		(fp_line
			(start 0.12065 0.3048)
			(end 0.67945 0.3048)
			(stroke
				(width 0.1)
				(type default)
			)
			(layer "B.Fab")
		)
		(fp_line
			(start -0.120396 0.3048)
			(end -0.120396 0.2794)
			(stroke
				(width 0.1)
				(type default)
			)
			(layer "B.Fab")
		)
		(fp_line
			(start -0.67945 0.3048)
			(end -0.120396 0.3048)
			(stroke
				(width 0.1)
				(type default)
			)
			(layer "B.Fab")
		)
		(pad "1" smd circle
			(at 0.40005 0 270)
			(size 0 0)
			(layers "B.Cu" "B.Mask" "B.Paste")
			(net "P0V9_CPU1_RT0_2A")
		)
		(pad "2" smd circle
			(at -0.40005 0 270)
			(size 0 0)
			(layers "B.Cu" "B.Mask" "B.Paste")
			(net "GND")
		)
	)
)
